# T6G (Grand Teton) — schematic netlist excerpt (pin names and nets, part order shuffled) for the footprints in the layout excerpt that follows; sources: Cadence DE-HDL packaged netlist, KiCad conversion of 04192023_DAF0TMB3IC0_F0TG_MB_C_brd_V02_OCP.brd

J1  SCONN288_DDR506112002KQ  IO  pkg DDR288S_1-1VXC  page 86
  VIN_BULK0  = P12V_MEM_CPU0
  RFU0  = NC
  VIN_MGMT  = P3V3_AUX
  HSCL  = I3C_SPD_DDRA_CPU0_SCL
  HSDA  = I3C_SPD_DDRA_CPU0_SDA
  VSS0  = GND
  DQ0_A  = M_A_CPU0_SA_DQ<0>
  VSS1  = GND
  DQ1_A  = M_A_CPU0_SA_DQ<1>
  VSS2  = GND
  DQS0_A_T  = M_A_CPU0_SA_DQS_DP<0>
  DQS0_A_C  = M_A_CPU0_SA_DQS_DN<0>
  VSS3  = GND
  DQ4_A  = M_A_CPU0_SA_DQ<4>
  VSS4  = GND
  DQ5_A  = M_A_CPU0_SA_DQ<5>
  VSS5  = GND
  DQ8_A  = M_A_CPU0_SA_DQ<8>
  VSS6  = GND
  DQ9_A  = M_A_CPU0_SA_DQ<9>
  VSS7  = GND
  DQS1_A_T  = M_A_CPU0_SA_DQS_DP<1>
  DQS1_A_C  = M_A_CPU0_SA_DQS_DN<1>
  VSS8  = GND
  DQ12_A  = M_A_CPU0_SA_DQ<12>
  VSS9  = GND
  DQ13_A  = M_A_CPU0_SA_DQ<13>
  VSS10  = GND
  DQ16_A  = M_A_CPU0_SA_DQ<16>
  VSS11  = GND
  DQ17_A  = M_A_CPU0_SA_DQ<17>
  VSS12  = GND
  DQS2_A_T  = M_A_CPU0_SA_DQS_DP<2>
  DQS2_A_C  = M_A_CPU0_SA_DQS_DN<2>
  VSS13  = GND
  DQ20_A  = M_A_CPU0_SA_DQ<20>
  VSS14  = GND
  DQ21_A  = M_A_CPU0_SA_DQ<21>
  VSS15  = GND
  DQ24_A  = M_A_CPU0_SA_DQ<24>
  VSS16  = GND
  DQ25_A  = M_A_CPU0_SA_DQ<25>
  VSS17  = GND
  DQS3_A_T  = M_A_CPU0_SA_DQS_DP<3>
  DQS3_A_C  = M_A_CPU0_SA_DQS_DN<3>
  VSS18  = GND
  DQ28_A  = M_A_CPU0_SA_DQ<28>
  VSS19  = GND
  DQ29_A  = M_A_CPU0_SA_DQ<29>
  VSS20  = GND
  CB0_A  = M_A_CPU0_SA_CB<0>
  VSS21  = GND
  CB1_A  = M_A_CPU0_SA_CB<1>
  VSS22  = GND
  DQS4_A_T  = M_A_CPU0_SA_DQS_DP<4>
  DQS4_A_C  = M_A_CPU0_SA_DQS_DN<4>
  VSS23  = GND
  CB4_A  = M_A_CPU0_SA_CB<4>
  VSS24  = GND
  CB5_A  = M_A_CPU0_SA_CB<5>
  VSS25  = GND
  ALERT_N  = M_A_CPU0_ALERT_N
  VSS26  = GND
  CS0_A_N  = M_A_CPU0_SA_CS_N<0>
  VSS27  = GND
  CA0_A  = M_A_CPU0_SA_CA<0>
  VSS28  = GND
  CA2_A  = M_A_CPU0_SA_CA<2>
  VSS29  = GND
  CA4_A  = M_A_CPU0_SA_CA<4>
  VSS30  = GND
  CA6_A  = M_A_CPU0_SA_CA<6>
  VSS31  = GND
  PAR_A  = M_A_CPU0_SA_PAR
  VSS32  = GND
  CA0_B  = M_A_CPU0_SB_CA<0>
  VSS33  = GND
  CA2_B  = M_A_CPU0_SB_CA<2>
  VSS34  = GND
  CA4_B  = M_A_CPU0_SB_CA<4>
  VSS35  = GND
  CA6_B  = M_A_CPU0_SB_CA<6>
  VSS36  = GND
  CS0_B_N  = M_A_CPU0_SB_CS_N<0>
  VSS37  = GND
  \lbd||rsp_a_n\  = M_A_CPU0_SA_RSP<0>
  \lbs||rsp_b_n\  = M_A_CPU0_SB_RSP<0>
  VSS38  = GND
  CB4_B  = M_A_CPU0_SB_CB<4>
  VSS39  = GND
  CB5_B  = M_A_CPU0_SB_CB<5>
  VSS40  = GND
  \dqs9_b_t||tdqs9_b_t||dbi4_b_n\  = M_A_CPU0_SB_DQS_DP<9>
  \dqs9_b_c||tdqs9_b_c\  = M_A_CPU0_SB_DQS_DN<9>
  VSS41  = GND
  CB0_B  = M_A_CPU0_SB_CB<0>
  VSS42  = GND
  CB1_B  = M_A_CPU0_SB_CB<1>
  VSS43  = GND
  DQ0_B  = M_A_CPU0_SB_DQ<0>
  VSS44  = GND
  DQ1_B  = M_A_CPU0_SB_DQ<1>
  VSS45  = GND
  DQS0_B_T  = M_A_CPU0_SB_DQS_DP<0>
  DQS0_B_C  = M_A_CPU0_SB_DQS_DN<0>
  VSS46  = GND
  DQ4_B  = M_A_CPU0_SB_DQ<4>
  VSS47  = GND
  DQ5_B  = M_A_CPU0_SB_DQ<5>
  VSS48  = GND
  DQ8_B  = M_A_CPU0_SB_DQ<8>
  VSS49  = GND
  DQ9_B  = M_A_CPU0_SB_DQ<9>
  VSS50  = GND
  DQS1_B_T  = M_A_CPU0_SB_DQS_DP<1>
  DQS1_B_C  = M_A_CPU0_SB_DQS_DN<1>
  VSS51  = GND
  DQ12_B  = M_A_CPU0_SB_DQ<12>
  VSS52  = GND
  DQ13_B  = M_A_CPU0_SB_DQ<13>
  VSS53  = GND
  DQ16_B  = M_A_CPU0_SB_DQ<16>
  VSS54  = GND
  DQ17_B  = M_A_CPU0_SB_DQ<17>
  VSS55  = GND
  DQS2_B_T  = M_A_CPU0_SB_DQS_DP<2>
  DQS2_B_C  = M_A_CPU0_SB_DQS_DN<2>
  VSS56  = GND
  DQ20_B  = M_A_CPU0_SB_DQ<20>
  VSS57  = GND
  DQ21_B  = M_A_CPU0_SB_DQ<21>
  VSS58  = GND
  DQ24_B  = M_A_CPU0_SB_DQ<24>
  VSS59  = GND
  DQ25_B  = M_A_CPU0_SB_DQ<25>
  VSS60  = GND
  DQS3_B_T  = M_A_CPU0_SB_DQS_DP<3>
  DQS3_B_C  = M_A_CPU0_SB_DQS_DN<3>
  VSS61  = GND
  DQ28_B  = M_A_CPU0_SB_DQ<28>
  VSS62  = GND
  DQ29_B  = M_A_CPU0_SB_DQ<29>
  VSS63  = GND
  RFU1  = NC
  VIN_BULK1  = P12V_MEM_CPU0
  VIN_BULK2  = P12V_MEM_CPU0
  \pwr_good||fail_n\  = PWRGD_CHA_CPU0_DIMM0
  HAS  = PD_CHA_CPU0_DIMM0_SAA
  RFU2  = NC
  RFU3  = NC
  VSS64  = GND
  DQ2_A  = M_A_CPU0_SA_DQ<2>
  VSS65  = GND
  DQ3_A  = M_A_CPU0_SA_DQ<3>
  VSS66  = GND
  \dqs5_a_c||tdqs5_a_c||dqs5_a_t||tdqs5_a_t\  = M_A_CPU0_SA_DQS_DN<5>
  \dqs5_a_t||tdqs5_a_t\  = M_A_CPU0_SA_DQS_DP<5>
  VSS67  = GND
  DQ6_A  = M_A_CPU0_SA_DQ<6>
  VSS68  = GND
  DQ7_A  = M_A_CPU0_SA_DQ<7>
  VSS69  = GND
  DQ10_A  = M_A_CPU0_SA_DQ<10>
  VSS70  = GND
  DQ11_A  = M_A_CPU0_SA_DQ<11>
  VSS71  = GND
  \dqs6_a_c||tdqs6_a_c||dqs6_a_t||tdqs6_a_t\  = M_A_CPU0_SA_DQS_DN<6>
  \dqs6_a_t||tdqs6_a_t\  = M_A_CPU0_SA_DQS_DP<6>
  VSS72  = GND
  DQ14_A  = M_A_CPU0_SA_DQ<14>
  VSS73  = GND
  DQ15_A  = M_A_CPU0_SA_DQ<15>
  VSS74  = GND
  DQ18_A  = M_A_CPU0_SA_DQ<18>
  VSS75  = GND
  DQ19_A  = M_A_CPU0_SA_DQ<19>
  VSS76  = GND
  \dqs7_a_c||tdqs7_a_c\  = M_A_CPU0_SA_DQS_DN<7>
  \dqs7_a_t||tdqs7_a_t\  = M_A_CPU0_SA_DQS_DP<7>
  VSS77  = GND
  DQ22_A  = M_A_CPU0_SA_DQ<22>
  VSS78  = GND
  DQ23_A  = M_A_CPU0_SA_DQ<23>
  VSS79  = GND
  DQ26_A  = M_A_CPU0_SA_DQ<26>
  VSS80  = GND
  DQ27_A  = M_A_CPU0_SA_DQ<27>
  VSS81  = GND
  \dqs8_a_c||tdqs8_a_c\  = M_A_CPU0_SA_DQS_DN<8>
  \dqs8_a_t||tdqs8_a_t\  = M_A_CPU0_SA_DQS_DP<8>
  VSS82  = GND
  DQ30_A  = M_A_CPU0_SA_DQ<30>
  VSS83  = GND
  DQ31_A  = M_A_CPU0_SA_DQ<31>
  VSS84  = GND
  CB2_A  = M_A_CPU0_SA_CB<2>
  VSS85  = GND
  CB3_A  = M_A_CPU0_SA_CB<3>
  VSS86  = GND
  \dqs9_a_c||tdqs9_a_c\  = M_A_CPU0_SA_DQS_DN<9>
  \dqs9_a_t||tdqs9_a_t\  = M_A_CPU0_SA_DQS_DP<9>
  VSS87  = GND
  CB6_A  = M_A_CPU0_SA_CB<6>
  VSS88  = GND
  CB7_A  = M_A_CPU0_SA_CB<7>
  VSS89  = GND
  RESET_N  = M_A_CPU0_RESET_N
  VSS90  = GND
  CS1_A_N  = M_A_CPU0_SA_CS_N<1>
  VSS91  = GND
  CA1_A  = M_A_CPU0_SA_CA<1>
  VSS92  = GND
  CA3_A  = M_A_CPU0_SA_CA<3>
  VSS93  = GND
  CA5_A  = M_A_CPU0_SA_CA<5>
  VSS94  = GND
  CK_T  = M_A_CPU0_CLK_DP<0>
  CK_C  = M_A_CPU0_CLK_DN<0>
  VSS95  = GND
  RFU4  = NC
  CA1_B  = M_A_CPU0_SB_CA<1>
  VSS96  = GND
  CA3_B  = M_A_CPU0_SB_CA<3>
  VSS97  = GND
  CA5_B  = M_A_CPU0_SB_CA<5>
  VSS98  = GND
  PAR_B  = M_A_CPU0_SB_PAR
  VSS99  = GND
  CS1_B_N  = M_A_CPU0_SB_CS_N<1>
  VSS100  = GND
  RFU5  = NC
  RFU6  = NC
  VSS101  = GND
  CB6_B  = M_A_CPU0_SB_CB<6>
  VSS102  = GND
  CB7_B  = M_A_CPU0_SB_CB<7>
  VSS103  = GND
  DQS4_B_C  = M_A_CPU0_SB_DQS_DN<4>
  DQS4_B_T  = M_A_CPU0_SB_DQS_DP<4>
  VSS104  = GND
  CB2_B  = M_A_CPU0_SB_CB<2>
  VSS105  = GND
  CB3_B  = M_A_CPU0_SB_CB<3>
  VSS106  = GND
  DQ2_B  = M_A_CPU0_SB_DQ<2>
  VSS107  = GND
  DQ3_B  = M_A_CPU0_SB_DQ<3>
  VSS108  = GND
  \dqs5_b_c||tdqs5_b_c\  = M_A_CPU0_SB_DQS_DN<5>
  \dqs5_b_t||tdqs5_b_t\  = M_A_CPU0_SB_DQS_DP<5>
  VSS109  = GND
  DQ6_B  = M_A_CPU0_SB_DQ<6>
  VSS110  = GND
  DQ7_B  = M_A_CPU0_SB_DQ<7>
  VSS111  = GND
  DQ10_B  = M_A_CPU0_SB_DQ<10>
  VSS112  = GND
  DQ11_B  = M_A_CPU0_SB_DQ<11>
  VSS113  = GND
  \dqs6_b_c||tdqs6_b_c\  = M_A_CPU0_SB_DQS_DN<6>
  \dqs6_b_t||tdqs6_b_t\  = M_A_CPU0_SB_DQS_DP<6>
  VSS114  = GND
  DQ14_B  = M_A_CPU0_SB_DQ<14>
  VSS115  = GND
  DQ15_B  = M_A_CPU0_SB_DQ<15>
  VSS116  = GND
  DQ18_B  = M_A_CPU0_SB_DQ<18>
  VSS117  = GND
  DQ19_B  = M_A_CPU0_SB_DQ<19>
  VSS118  = GND
  \dqs7_b_c||tdqs7_b_c\  = M_A_CPU0_SB_DQS_DN<7>
  \dqs7_b_t||tdqs7_b_t\  = M_A_CPU0_SB_DQS_DP<7>
  VSS119  = GND
  DQ22_B  = M_A_CPU0_SB_DQ<22>
  VSS120  = GND
  DQ23_B  = M_A_CPU0_SB_DQ<23>
  VSS121  = GND
  DQ26_B  = M_A_CPU0_SB_DQ<26>
  VSS122  = GND
  DQ27_B  = M_A_CPU0_SB_DQ<27>
  VSS123  = GND
  \dqs8_b_c||tdqs8_b_c\  = M_A_CPU0_SB_DQS_DN<8>
  \dqs8_b_t||tdqs8_b_t\  = M_A_CPU0_SB_DQS_DP<8>
  VSS124  = GND
  DQ30_B  = M_A_CPU0_SB_DQ<30>
  VSS125  = GND
  DQ31_B  = M_A_CPU0_SB_DQ<31>
  VSS126  = GND
  G1  = GND
  G2  = GND
  G3  = GND

(kicad_pcb
	(version 20260206)
	(generator "pcbnew")
	(generator_version "10.0")
	(general
		(thickness 1.6)
		(legacy_teardrops no)
	)
	(paper "A4")
	(title_block
		(title "04192023_DAF0TMB3IC0_F0TG_MB_C_brd_V02_OCP.brd")
		(comment 1 "Grand Teton / footprint 2352 of 8354 (J1), pads 1-46 of 291")
	)
	(layers
		(0 "F.Cu" signal "TOP")
		(4 "In1.Cu" signal "GND")
		(6 "In2.Cu" signal "IN1")
		(8 "In3.Cu" signal "GND1")
		(10 "In4.Cu" signal "IN2")
		(12 "In5.Cu" signal "GND2")
		(14 "In6.Cu" signal "IN3")
		(16 "In7.Cu" signal "GND3")
		(18 "In8.Cu" signal "VCC")
		(20 "In9.Cu" signal "VCC1")
		(22 "In10.Cu" signal "GND4")
		(24 "In11.Cu" signal "IN4")
		(26 "In12.Cu" signal "GND5")
		(28 "In13.Cu" signal "IN5")
		(30 "In14.Cu" signal "GND6")
		(32 "In15.Cu" signal "IN6")
		(34 "In16.Cu" signal "GND7")
		(2 "B.Cu" signal "BOTTOM")
		(9 "F.Adhes" user "F.Adhesive")
		(11 "B.Adhes" user "B.Adhesive")
		(13 "F.Paste" user "Package Geometry/Pastemask Top")
		(15 "B.Paste" user "Package Geometry/Pastemask Bottom")
		(5 "F.SilkS" user "Ref Des/Silkscreen Top")
		(7 "B.SilkS" user "Ref Des/Silkscreen Bottom")
		(1 "F.Mask" user "Board Geometry/Soldermask Top")
		(3 "B.Mask" user "Board Geometry/Soldermask Bottom")
		(17 "Dwgs.User" user "User.Drawings")
		(19 "Cmts.User" user "User.Comments")
		(21 "Eco1.User" user "User.Eco1")
		(23 "Eco2.User" user "User.Eco2")
		(25 "Edge.Cuts" user "Board Geometry/Outline")
		(27 "Margin" user)
		(31 "F.CrtYd" user "Package Geometry/Place Bound Top")
		(29 "B.CrtYd" user "Package Geometry/Place Bound Bottom")
		(35 "F.Fab" user "Ref Des/Assembly Top")
		(33 "B.Fab" user "Ref Des/Assembly Bottom")
	)
	(footprint ""
		(layer "F.Cu")
		(at 305.31816 -255.560068 180)
		(property "Reference" "J1"
			(at -2.2098 -81.984088 0)
			(unlocked yes)
			(layer "F.SilkS")
			(effects
				(font
					(size 0.7874 0.5842)
					(thickness 0.1524)
				)
			)
		)
		(property "Value" ""
			(at 0 0 180)
			(layer "F.Fab")
			(effects
				(font
					(size 1.27 1.27)
				)
			)
		)
		(duplicate_pad_numbers_are_jumpers no)
		(pad "1" smd rect
			(at -2.050034 -63.324994 90)
			(size 0.519938 1.4986)
			(layers "F.Cu" "F.Mask" "F.Paste")
			(net "P12V_MEM_CPU0")
		)
		(pad "2" smd rect
			(at -2.050034 -62.47511 90)
			(size 0.519938 1.4986)
			(layers "F.Cu" "F.Mask" "F.Paste")
			(net "Net_2249")
		)
		(pad "3" smd rect
			(at -2.050034 -61.624972 90)
			(size 0.519938 1.4986)
			(layers "F.Cu" "F.Mask" "F.Paste")
			(net "P3V3_AUX")
		)
		(pad "4" smd rect
			(at -2.050034 -60.775088 90)
			(size 0.519938 1.4986)
			(layers "F.Cu" "F.Mask" "F.Paste")
			(net "I3C_SPD_DDRA_CPU0_SCL")
		)
		(pad "5" smd rect
			(at -2.050034 -59.92495 90)
			(size 0.519938 1.4986)
			(layers "F.Cu" "F.Mask" "F.Paste")
			(net "I3C_SPD_DDRA_CPU0_SDA")
		)
		(pad "6" smd rect
			(at -2.050034 -59.075066 90)
			(size 0.519938 1.4986)
			(layers "F.Cu" "F.Mask" "F.Paste")
			(net "GND")
		)
		(pad "7" smd rect
			(at -2.050034 -58.224928 90)
			(size 0.519938 1.4986)
			(layers "F.Cu" "F.Mask" "F.Paste")
			(net "M_A_CPU0_SA_DQ<0>")
		)
		(pad "8" smd rect
			(at -2.050034 -57.375044 90)
			(size 0.519938 1.4986)
			(layers "F.Cu" "F.Mask" "F.Paste")
			(net "GND")
		)
		(pad "9" smd rect
			(at -2.050034 -56.524906 90)
			(size 0.519938 1.4986)
			(layers "F.Cu" "F.Mask" "F.Paste")
			(net "M_A_CPU0_SA_DQ<1>")
		)
		(pad "10" smd rect
			(at -2.050034 -55.675022 90)
			(size 0.519938 1.4986)
			(layers "F.Cu" "F.Mask" "F.Paste")
			(net "GND")
		)
		(pad "11" smd rect
			(at -2.050034 -54.824884 90)
			(size 0.519938 1.4986)
			(layers "F.Cu" "F.Mask" "F.Paste")
			(net "M_A_CPU0_SA_DQS_DP<0>")
		)
		(pad "12" smd rect
			(at -2.050034 -53.975 90)
			(size 0.519938 1.4986)
			(layers "F.Cu" "F.Mask" "F.Paste")
			(net "M_A_CPU0_SA_DQS_DN<0>")
		)
		(pad "13" smd rect
			(at -2.050034 -53.125116 90)
			(size 0.519938 1.4986)
			(layers "F.Cu" "F.Mask" "F.Paste")
			(net "GND")
		)
		(pad "14" smd rect
			(at -2.050034 -52.274978 90)
			(size 0.519938 1.4986)
			(layers "F.Cu" "F.Mask" "F.Paste")
			(net "M_A_CPU0_SA_DQ<4>")
		)
		(pad "15" smd rect
			(at -2.050034 -51.425094 90)
			(size 0.519938 1.4986)
			(layers "F.Cu" "F.Mask" "F.Paste")
			(net "GND")
		)
		(pad "16" smd rect
			(at -2.050034 -50.574956 90)
			(size 0.519938 1.4986)
			(layers "F.Cu" "F.Mask" "F.Paste")
			(net "M_A_CPU0_SA_DQ<5>")
		)
		(pad "17" smd rect
			(at -2.050034 -49.725072 90)
			(size 0.519938 1.4986)
			(layers "F.Cu" "F.Mask" "F.Paste")
			(net "GND")
		)
		(pad "18" smd rect
			(at -2.050034 -48.874934 90)
			(size 0.519938 1.4986)
			(layers "F.Cu" "F.Mask" "F.Paste")
			(net "M_A_CPU0_SA_DQ<8>")
		)
		(pad "19" smd rect
			(at -2.050034 -48.02505 90)
			(size 0.519938 1.4986)
			(layers "F.Cu" "F.Mask" "F.Paste")
			(net "GND")
		)
		(pad "20" smd rect
			(at -2.050034 -47.174912 90)
			(size 0.519938 1.4986)
			(layers "F.Cu" "F.Mask" "F.Paste")
			(net "M_A_CPU0_SA_DQ<9>")
		)
		(pad "21" smd rect
			(at -2.050034 -46.325028 90)
			(size 0.519938 1.4986)
			(layers "F.Cu" "F.Mask" "F.Paste")
			(net "GND")
		)
		(pad "22" smd rect
			(at -2.050034 -45.47489 90)
			(size 0.519938 1.4986)
			(layers "F.Cu" "F.Mask" "F.Paste")
			(net "M_A_CPU0_SA_DQS_DP<1>")
		)
		(pad "23" smd rect
			(at -2.050034 -44.625006 90)
			(size 0.519938 1.4986)
			(layers "F.Cu" "F.Mask" "F.Paste")
			(net "M_A_CPU0_SA_DQS_DN<1>")
		)
		(pad "24" smd rect
			(at -2.050034 -43.775122 90)
			(size 0.519938 1.4986)
			(layers "F.Cu" "F.Mask" "F.Paste")
			(net "GND")
		)
		(pad "25" smd rect
			(at -2.050034 -42.924984 90)
			(size 0.519938 1.4986)
			(layers "F.Cu" "F.Mask" "F.Paste")
			(net "M_A_CPU0_SA_DQ<12>")
		)
		(pad "26" smd rect
			(at -2.050034 -42.0751 90)
			(size 0.519938 1.4986)
			(layers "F.Cu" "F.Mask" "F.Paste")
			(net "GND")
		)
		(pad "27" smd rect
			(at -2.050034 -41.224962 90)
			(size 0.519938 1.4986)
			(layers "F.Cu" "F.Mask" "F.Paste")
			(net "M_A_CPU0_SA_DQ<13>")
		)
		(pad "28" smd rect
			(at -2.050034 -40.375078 90)
			(size 0.519938 1.4986)
			(layers "F.Cu" "F.Mask" "F.Paste")
			(net "GND")
		)
		(pad "29" smd rect
			(at -2.050034 -39.52494 90)
			(size 0.519938 1.4986)
			(layers "F.Cu" "F.Mask" "F.Paste")
			(net "M_A_CPU0_SA_DQ<16>")
		)
		(pad "30" smd rect
			(at -2.050034 -38.675056 90)
			(size 0.519938 1.4986)
			(layers "F.Cu" "F.Mask" "F.Paste")
			(net "GND")
		)
		(pad "31" smd rect
			(at -2.050034 -37.824918 90)
			(size 0.519938 1.4986)
			(layers "F.Cu" "F.Mask" "F.Paste")
			(net "M_A_CPU0_SA_DQ<17>")
		)
		(pad "32" smd rect
			(at -2.050034 -36.975034 90)
			(size 0.519938 1.4986)
			(layers "F.Cu" "F.Mask" "F.Paste")
			(net "GND")
		)
		(pad "33" smd rect
			(at -2.050034 -36.124896 90)
			(size 0.519938 1.4986)
			(layers "F.Cu" "F.Mask" "F.Paste")
			(net "M_A_CPU0_SA_DQS_DP<2>")
		)
		(pad "34" smd rect
			(at -2.050034 -35.275012 90)
			(size 0.519938 1.4986)
			(layers "F.Cu" "F.Mask" "F.Paste")
			(net "M_A_CPU0_SA_DQS_DN<2>")
		)
		(pad "35" smd rect
			(at -2.050034 -34.425128 90)
			(size 0.519938 1.4986)
			(layers "F.Cu" "F.Mask" "F.Paste")
			(net "GND")
		)
		(pad "36" smd rect
			(at -2.050034 -33.57499 90)
			(size 0.519938 1.4986)
			(layers "F.Cu" "F.Mask" "F.Paste")
			(net "M_A_CPU0_SA_DQ<20>")
		)
		(pad "37" smd rect
			(at -2.050034 -32.725106 90)
			(size 0.519938 1.4986)
			(layers "F.Cu" "F.Mask" "F.Paste")
			(net "GND")
		)
		(pad "38" smd rect
			(at -2.050034 -31.874968 90)
			(size 0.519938 1.4986)
			(layers "F.Cu" "F.Mask" "F.Paste")
			(net "M_A_CPU0_SA_DQ<21>")
		)
		(pad "39" smd rect
			(at -2.050034 -31.025084 90)
			(size 0.519938 1.4986)
			(layers "F.Cu" "F.Mask" "F.Paste")
			(net "GND")
		)
		(pad "40" smd rect
			(at -2.050034 -30.174946 90)
			(size 0.519938 1.4986)
			(layers "F.Cu" "F.Mask" "F.Paste")
			(net "M_A_CPU0_SA_DQ<24>")
		)
		(pad "41" smd rect
			(at -2.050034 -29.325062 90)
			(size 0.519938 1.4986)
			(layers "F.Cu" "F.Mask" "F.Paste")
			(net "GND")
		)
		(pad "42" smd rect
			(at -2.050034 -28.474924 90)
			(size 0.519938 1.4986)
			(layers "F.Cu" "F.Mask" "F.Paste")
			(net "M_A_CPU0_SA_DQ<25>")
		)
		(pad "43" smd rect
			(at -2.050034 -27.62504 90)
			(size 0.519938 1.4986)
			(layers "F.Cu" "F.Mask" "F.Paste")
			(net "GND")
		)
		(pad "44" smd rect
			(at -2.050034 -26.774902 90)
			(size 0.519938 1.4986)
			(layers "F.Cu" "F.Mask" "F.Paste")
			(net "M_A_CPU0_SA_DQS_DP<3>")
		)
		(pad "45" smd rect
			(at -2.050034 -25.925018 90)
			(size 0.519938 1.4986)
			(layers "F.Cu" "F.Mask" "F.Paste")
			(net "M_A_CPU0_SA_DQS_DN<3>")
		)
		(pad "46" smd rect
			(at -2.050034 -25.07488 90)
			(size 0.519938 1.4986)
			(layers "F.Cu" "F.Mask" "F.Paste")
			(net "GND")
		)
	)
)
